# T6G (Grand Teton) — schematic netlist excerpt (pin names and nets, part order shuffled) for the footprints in the layout excerpt that follows; sources: Cadence DE-HDL packaged netlist, KiCad conversion of 04192023_DAF0TMB3IC0_F0TG_MB_C_brd_V02_OCP.brd

R1491  Q_RES  10K 5% EMPTY  pkg 0402LF  page 188 : A = P3V3 ; B = PWRGD_P3V3_EN_R
R9017  Q_RES  4.7K 5% CHIP  pkg 0402LF  page 123 : A = P3V3_AUX ; B = PRSNT_CABLE_GPU_A3_ISO_N

(kicad_pcb
	(version 20260206)
	(generator "pcbnew")
	(generator_version "10.0")
	(general
		(thickness 1.6)
		(legacy_teardrops no)
	)
	(paper "A4")
	(title_block
		(title "04192023_DAF0TMB3IC0_F0TG_MB_C_brd_V02_OCP.brd")
		(comment 1 "Grand Teton / footprints 416-417 of 8354")
	)
	(layers
		(0 "F.Cu" signal "TOP")
		(4 "In1.Cu" signal "GND")
		(6 "In2.Cu" signal "IN1")
		(8 "In3.Cu" signal "GND1")
		(10 "In4.Cu" signal "IN2")
		(12 "In5.Cu" signal "GND2")
		(14 "In6.Cu" signal "IN3")
		(16 "In7.Cu" signal "GND3")
		(18 "In8.Cu" signal "VCC")
		(20 "In9.Cu" signal "VCC1")
		(22 "In10.Cu" signal "GND4")
		(24 "In11.Cu" signal "IN4")
		(26 "In12.Cu" signal "GND5")
		(28 "In13.Cu" signal "IN5")
		(30 "In14.Cu" signal "GND6")
		(32 "In15.Cu" signal "IN6")
		(34 "In16.Cu" signal "GND7")
		(2 "B.Cu" signal "BOTTOM")
		(9 "F.Adhes" user "F.Adhesive")
		(11 "B.Adhes" user "B.Adhesive")
		(13 "F.Paste" user "Package Geometry/Pastemask Top")
		(15 "B.Paste" user "Package Geometry/Pastemask Bottom")
		(5 "F.SilkS" user "Ref Des/Silkscreen Top")
		(7 "B.SilkS" user "Ref Des/Silkscreen Bottom")
		(1 "F.Mask" user "Board Geometry/Soldermask Top")
		(3 "B.Mask" user "Board Geometry/Soldermask Bottom")
		(17 "Dwgs.User" user "User.Drawings")
		(19 "Cmts.User" user "User.Comments")
		(21 "Eco1.User" user "User.Eco1")
		(23 "Eco2.User" user "User.Eco2")
		(25 "Edge.Cuts" user "Board Geometry/Outline")
		(27 "Margin" user)
		(31 "F.CrtYd" user "Package Geometry/Place Bound Top")
		(29 "B.CrtYd" user "Package Geometry/Place Bound Bottom")
		(35 "F.Fab" user "Ref Des/Assembly Top")
		(33 "B.Fab" user "Ref Des/Assembly Bottom")
	)
	(footprint ""
		(layer "F.Cu")
		(at 364.314486 -408.931364)
		(property "Reference" "R9017"
			(at 0 0 0)
			(layer "F.SilkS")
			(hide yes)
			(effects
				(font
					(size 1.27 1.27)
				)
			)
		)
		(property "Value" ""
			(at 0 0 0)
			(layer "F.Fab")
			(effects
				(font
					(size 1.27 1.27)
				)
			)
		)
		(duplicate_pad_numbers_are_jumpers no)
		(fp_line
			(start -0.7874 -0.4064)
			(end 0.7874 -0.4064)
			(stroke
				(width 0.1524)
				(type default)
			)
			(layer "F.SilkS")
		)
		(fp_line
			(start -0.7874 0.4064)
			(end -0.7874 -0.4064)
			(stroke
				(width 0.1524)
				(type default)
			)
			(layer "F.SilkS")
		)
		(fp_line
			(start 0.7874 -0.4064)
			(end 0.7874 0.4064)
			(stroke
				(width 0.1524)
				(type default)
			)
			(layer "F.SilkS")
		)
		(fp_line
			(start 0.7874 0.4064)
			(end -0.7874 0.4064)
			(stroke
				(width 0.1524)
				(type default)
			)
			(layer "F.SilkS")
		)
		(fp_line
			(start -0.67945 -0.305054)
			(end -0.12065 -0.305054)
			(stroke
				(width 0.1)
				(type default)
			)
			(layer "F.Fab")
		)
		(fp_line
			(start -0.67945 0.3048)
			(end -0.67945 -0.305054)
			(stroke
				(width 0.1)
				(type default)
			)
			(layer "F.Fab")
		)
		(fp_line
			(start -0.12065 -0.305054)
			(end -0.12065 -0.2794)
			(stroke
				(width 0.1)
				(type default)
			)
			(layer "F.Fab")
		)
		(fp_line
			(start -0.12065 -0.2794)
			(end 0.12065 -0.2794)
			(stroke
				(width 0.1)
				(type default)
			)
			(layer "F.Fab")
		)
		(fp_line
			(start -0.12065 0.2794)
			(end -0.12065 0.3048)
			(stroke
				(width 0.1)
				(type default)
			)
			(layer "F.Fab")
		)
		(fp_line
			(start -0.12065 0.3048)
			(end -0.67945 0.3048)
			(stroke
				(width 0.1)
				(type default)
			)
			(layer "F.Fab")
		)
		(fp_line
			(start 0.120396 0.2794)
			(end -0.12065 0.2794)
			(stroke
				(width 0.1)
				(type default)
			)
			(layer "F.Fab")
		)
		(fp_line
			(start 0.120396 0.3048)
			(end 0.120396 0.2794)
			(stroke
				(width 0.1)
				(type default)
			)
			(layer "F.Fab")
		)
		(fp_line
			(start 0.12065 -0.3048)
			(end 0.67945 -0.3048)
			(stroke
				(width 0.1)
				(type default)
			)
			(layer "F.Fab")
		)
		(fp_line
			(start 0.12065 -0.2794)
			(end 0.12065 -0.3048)
			(stroke
				(width 0.1)
				(type default)
			)
			(layer "F.Fab")
		)
		(fp_line
			(start 0.67945 -0.3048)
			(end 0.67945 0.3048)
			(stroke
				(width 0.1)
				(type default)
			)
			(layer "F.Fab")
		)
		(fp_line
			(start 0.67945 0.3048)
			(end 0.120396 0.3048)
			(stroke
				(width 0.1)
				(type default)
			)
			(layer "F.Fab")
		)
		(pad "1" smd circle
			(at -0.40005 0)
			(size 0 0)
			(layers "F.Cu" "F.Mask" "F.Paste")
			(net "P3V3_AUX")
		)
		(pad "2" smd circle
			(at 0.40005 0)
			(size 0 0)
			(layers "F.Cu" "F.Mask" "F.Paste")
			(net "PRSNT_CABLE_GPU_A3_ISO_N")
		)
	)
	(footprint ""
		(layer "F.Cu")
		(at 112.649 -123.952 90)
		(property "Reference" "R1491"
			(at 0 0 90)
			(layer "F.SilkS")
			(hide yes)
			(effects
				(font
					(size 1.27 1.27)
				)
			)
		)
		(property "Value" ""
			(at 0 0 90)
			(layer "F.Fab")
			(effects
				(font
					(size 1.27 1.27)
				)
			)
		)
		(duplicate_pad_numbers_are_jumpers no)
		(fp_line
			(start 0.7874 -0.4064)
			(end 0.7874 0.4064)
			(stroke
				(width 0.1524)
				(type default)
			)
			(layer "F.SilkS")
		)
		(fp_line
			(start -0.7874 -0.4064)
			(end 0.7874 -0.4064)
			(stroke
				(width 0.1524)
				(type default)
			)
			(layer "F.SilkS")
		)
		(fp_line
			(start 0.7874 0.4064)
			(end -0.7874 0.4064)
			(stroke
				(width 0.1524)
				(type default)
			)
			(layer "F.SilkS")
		)
		(fp_line
			(start -0.7874 0.4064)
			(end -0.7874 -0.4064)
			(stroke
				(width 0.1524)
				(type default)
			)
			(layer "F.SilkS")
		)
		(fp_line
			(start -0.12065 -0.305054)
			(end -0.12065 -0.2794)
			(stroke
				(width 0.1)
				(type default)
			)
			(layer "F.Fab")
		)
		(fp_line
			(start -0.67945 -0.305054)
			(end -0.12065 -0.305054)
			(stroke
				(width 0.1)
				(type default)
			)
			(layer "F.Fab")
		)
		(fp_line
			(start 0.67945 -0.3048)
			(end 0.67945 0.3048)
			(stroke
				(width 0.1)
				(type default)
			)
			(layer "F.Fab")
		)
		(fp_line
			(start 0.12065 -0.3048)
			(end 0.67945 -0.3048)
			(stroke
				(width 0.1)
				(type default)
			)
			(layer "F.Fab")
		)
		(fp_line
			(start 0.12065 -0.2794)
			(end 0.12065 -0.3048)
			(stroke
				(width 0.1)
				(type default)
			)
			(layer "F.Fab")
		)
		(fp_line
			(start -0.12065 -0.2794)
			(end 0.12065 -0.2794)
			(stroke
				(width 0.1)
				(type default)
			)
			(layer "F.Fab")
		)
		(fp_line
			(start 0.120396 0.2794)
			(end -0.12065 0.2794)
			(stroke
				(width 0.1)
				(type default)
			)
			(layer "F.Fab")
		)
		(fp_line
			(start -0.12065 0.2794)
			(end -0.12065 0.3048)
			(stroke
				(width 0.1)
				(type default)
			)
			(layer "F.Fab")
		)
		(fp_line
			(start 0.67945 0.3048)
			(end 0.120396 0.3048)
			(stroke
				(width 0.1)
				(type default)
			)
			(layer "F.Fab")
		)
		(fp_line
			(start 0.120396 0.3048)
			(end 0.120396 0.2794)
			(stroke
				(width 0.1)
				(type default)
			)
			(layer "F.Fab")
		)
		(fp_line
			(start -0.12065 0.3048)
			(end -0.67945 0.3048)
			(stroke
				(width 0.1)
				(type default)
			)
			(layer "F.Fab")
		)
		(fp_line
			(start -0.67945 0.3048)
			(end -0.67945 -0.305054)
			(stroke
				(width 0.1)
				(type default)
			)
			(layer "F.Fab")
		)
		(pad "1" smd circle
			(at -0.40005 0 90)
			(size 0 0)
			(layers "F.Cu" "F.Mask" "F.Paste")
			(net "P3V3")
		)
		(pad "2" smd circle
			(at 0.40005 0 90)
			(size 0 0)
			(layers "F.Cu" "F.Mask" "F.Paste")
			(net "PWRGD_P3V3_EN_R")
		)
	)
)
